#ISCELL
  mstr_symbols cad_note *
  *
#ISCELL
  mstr_symbols intel_corp_bpage *
  *
#ISCELL
  mstr_symbols vcc_core *
  page101_i100
#ISCELL
  mstr_symbols vcc_core *
  page101_i101
#ISCELL
  mstr_symbols vcc_core *
  page101_i102
#ISCELL
  mstr_symbols vcc_core *
  page101_i103
#CELL
  dev_discrete cap_a *
  page101_i104
#CELL
  mstr_discrete res *
  page101_i105
#CELL
  dev_discrete cap_a *
  page101_i106
#ISCELL
  mstr_symbols gnd *
  page101_i107
#ISCELL
  mstr_symbols gnd *
  page101_i108
#CELL
  dev_discrete cap_a *
  page101_i109
#CELL
  dev_discrete cap_a *
  page101_i110
#CELL
  dev_discrete cap_a *
  page101_i111
#CELL
  dev_discrete cap_a *
  page101_i112
#CELL
  mstr_discrete cap *
  page101_i113
#CELL
  mstr_discrete ferrite *
  page101_i114
#ISCELL
  mstr_symbols p3v3_stby *
  page101_i115
#CELL
  dev_discrete cap_a *
  page101_i116
#ISCELL
  mstr_symbols vcc_core *
  page101_i117
#ISCELL
  mstr_symbols vcc_core *
  page101_i118
#ISCELL
  mstr_symbols vcc_core *
  page101_i119
#ISCELL
  mstr_symbols vcc_core *
  page101_i120
#ISCELL
  mstr_symbols vcc_core *
  page101_i121
#ISCELL
  mstr_symbols vcc_core *
  page101_i122
#ISCELL
  mstr_symbols vcc_core *
  page101_i123
#CELL
  mstr_discrete res *
  page101_i124
#CELL
  mstr_discrete res *
  page101_i125
#CELL
  mstr_discrete res *
  page101_i129
#ISCELL
  mstr_standard offpage *
  page101_i13
#CELL
  mstr_discrete res *
  page101_i130
#CELL
  mstr_discrete res *
  page101_i131
#CELL
  mstr_discrete res *
  page101_i132
#CELL
  mstr_discrete res *
  page101_i133
#ISCELL
  mstr_standard offpage *
  page101_i14
#CELL
  mstr_discrete res *
  page101_i20
#CELL
  mstr_discrete res *
  page101_i28
#ISCELL
  mstr_symbols gnd *
  page101_i29
#ISCELL
  mstr_symbols gnd *
  page101_i33
#CELL
  mstr_clock ics9fgp204 *
  page101_i34
#CELL
  mstr_discrete res *
  page101_i48
#CELL
  mstr_discrete cap *
  page101_i49
#CELL
  mstr_discrete crystal *
  page101_i52
#CELL
  mstr_discrete cap *
  page101_i53
#ISCELL
  mstr_symbols gnd *
  page101_i54
#ISCELL
  mstr_standard offpage *
  page101_i55
#ISCELL
  mstr_symbols gnd *
  page101_i58
#ISCELL
  mstr_standard offpage *
  page101_i59
#ISCELL
  mstr_standard offpage *
  page101_i60
#ISCELL
  mstr_symbols gnd *
  page101_i64
#ISCELL
  mstr_standard offpage *
  page101_i71
#ISCELL
  mstr_standard offpage *
  page101_i72
#ISCELL
  mstr_standard offpage *
  page101_i79
#ISCELL
  mstr_standard offpage *
  page101_i80
#ISCELL
  mstr_standard offpage *
  page101_i81
#ISCELL
  mstr_standard offpage *
  page101_i87
#CELL
  dev_discrete cap_a *
  page101_i89
#CELL
  dev_discrete cap_a *
  page101_i90
#CELL
  mstr_discrete res *
  page101_i94
#CELL
  mstr_discrete res *
  page101_i95
#ISCELL
  mstr_symbols gnd *
  page101_i96
#CELL
  dev_discrete cap_a *
  page101_i97
#ISCELL
  mstr_symbols gnd *
  page101_i98
#CELL
  dev_discrete cap_a *
  page101_i99
